(kicad_pcb
	(version 20260206)
	(generator "pcbnew")
	(generator_version "10.0")
	(general
		(thickness 1.6)
		(legacy_teardrops no)
	)
	(paper "A4")
	(title_block
		(title "03242023_DA0F0TMBIJ0_F0T_Motherboard_J_brd_V01_OCP.brd")
		(comment 1 "Grand Teton / footprint 1952 of 6105 (J11), pads 1-112 of 291")
	)
	(layers
		(0 "F.Cu" signal "TOP")
		(4 "In1.Cu" signal "GND")
		(6 "In2.Cu" signal "IN1")
		(8 "In3.Cu" signal "GND1")
		(10 "In4.Cu" signal "IN2")
		(12 "In5.Cu" signal "GND2")
		(14 "In6.Cu" signal "IN3")
		(16 "In7.Cu" signal "GND3")
		(18 "In8.Cu" signal "VCC")
		(20 "In9.Cu" signal "VCC1")
		(22 "In10.Cu" signal "GND4")
		(24 "In11.Cu" signal "IN4")
		(26 "In12.Cu" signal "GND5")
		(28 "In13.Cu" signal "IN5")
		(30 "In14.Cu" signal "GND6")
		(32 "In15.Cu" signal "IN6")
		(34 "In16.Cu" signal "GND7")
		(2 "B.Cu" signal "BOTTOM")
		(9 "F.Adhes" user "F.Adhesive")
		(11 "B.Adhes" user "B.Adhesive")
		(13 "F.Paste" user "Package Geometry/Pastemask Top")
		(15 "B.Paste" user "Package Geometry/Pastemask Bottom")
		(5 "F.SilkS" user "Ref Des/Silkscreen Top")
		(7 "B.SilkS" user "Ref Des/Silkscreen Bottom")
		(1 "F.Mask" user "Board Geometry/Soldermask Top")
		(3 "B.Mask" user "Board Geometry/Soldermask Bottom")
		(17 "Dwgs.User" user "User.Drawings")
		(19 "Cmts.User" user "User.Comments")
		(21 "Eco1.User" user "User.Eco1")
		(23 "Eco2.User" user "User.Eco2")
		(25 "Edge.Cuts" user "Board Geometry/Outline")
		(27 "Margin" user)
		(31 "F.CrtYd" user "Package Geometry/Place Bound Top")
		(29 "B.CrtYd" user "Package Geometry/Place Bound Bottom")
		(35 "F.Fab" user "Ref Des/Assembly Top")
		(33 "B.Fab" user "Ref Des/Assembly Bottom")
	)
	(footprint ""
		(layer "F.Cu")
		(at 431.434748 -258.091686)
		(property "Reference" "J11"
			(at -3.683 -81.702148 0)
			(unlocked yes)
			(layer "F.SilkS")
			(effects
				(font
					(size 0.7874 0.5842)
					(thickness 0.1524)
				)
				(justify left)
			)
		)
		(property "Value" ""
			(at 0 0 0)
			(layer "F.Fab")
			(effects
				(font
					(size 1.27 1.27)
				)
			)
		)
		(duplicate_pad_numbers_are_jumpers no)
		(pad "1" smd rect
			(at -2.050034 -63.324994 270)
			(size 0.519938 1.4986)
			(layers "F.Cu" "F.Mask" "F.Paste")
			(net "P12V_S3_AUX_CPU0_NVDIMM")
		)
		(pad "2" smd rect
			(at -2.050034 -62.47511 270)
			(size 0.519938 1.4986)
			(layers "F.Cu" "F.Mask" "F.Paste")
			(net "TP_CHF_CPU0_DIMM1_FRU_0")
		)
		(pad "3" smd rect
			(at -2.050034 -61.624972 270)
			(size 0.519938 1.4986)
			(layers "F.Cu" "F.Mask" "F.Paste")
			(net "P3V3_AUX")
		)
		(pad "4" smd rect
			(at -2.050034 -60.775088 270)
			(size 0.519938 1.4986)
			(layers "F.Cu" "F.Mask" "F.Paste")
			(net "I3C_SPD_DDREFGH_CPU0_LVC1_SCL_2")
		)
		(pad "5" smd rect
			(at -2.050034 -59.92495 270)
			(size 0.519938 1.4986)
			(layers "F.Cu" "F.Mask" "F.Paste")
			(net "I3C_SPD_DDREFGH_CPU0_LVC1_SDA")
		)
		(pad "6" smd rect
			(at -2.050034 -59.075066 270)
			(size 0.519938 1.4986)
			(layers "F.Cu" "F.Mask" "F.Paste")
			(net "GND")
		)
		(pad "7" smd rect
			(at -2.050034 -58.224928 270)
			(size 0.519938 1.4986)
			(layers "F.Cu" "F.Mask" "F.Paste")
			(net "M_F_CPU0_SA_DQ<0>")
		)
		(pad "8" smd rect
			(at -2.050034 -57.375044 270)
			(size 0.519938 1.4986)
			(layers "F.Cu" "F.Mask" "F.Paste")
			(net "GND")
		)
		(pad "9" smd rect
			(at -2.050034 -56.524906 270)
			(size 0.519938 1.4986)
			(layers "F.Cu" "F.Mask" "F.Paste")
			(net "M_F_CPU0_SA_DQ<1>")
		)
		(pad "10" smd rect
			(at -2.050034 -55.675022 270)
			(size 0.519938 1.4986)
			(layers "F.Cu" "F.Mask" "F.Paste")
			(net "GND")
		)
		(pad "11" smd rect
			(at -2.050034 -54.824884 270)
			(size 0.519938 1.4986)
			(layers "F.Cu" "F.Mask" "F.Paste")
			(net "M_F_CPU0_SA_DQS_DP<0>")
		)
		(pad "12" smd rect
			(at -2.050034 -53.975 270)
			(size 0.519938 1.4986)
			(layers "F.Cu" "F.Mask" "F.Paste")
			(net "M_F_CPU0_SA_DQS_DN<0>")
		)
		(pad "13" smd rect
			(at -2.050034 -53.125116 270)
			(size 0.519938 1.4986)
			(layers "F.Cu" "F.Mask" "F.Paste")
			(net "GND")
		)
		(pad "14" smd rect
			(at -2.050034 -52.274978 270)
			(size 0.519938 1.4986)
			(layers "F.Cu" "F.Mask" "F.Paste")
			(net "M_F_CPU0_SA_DQ<4>")
		)
		(pad "15" smd rect
			(at -2.050034 -51.425094 270)
			(size 0.519938 1.4986)
			(layers "F.Cu" "F.Mask" "F.Paste")
			(net "GND")
		)
		(pad "16" smd rect
			(at -2.050034 -50.574956 270)
			(size 0.519938 1.4986)
			(layers "F.Cu" "F.Mask" "F.Paste")
			(net "M_F_CPU0_SA_DQ<5>")
		)
		(pad "17" smd rect
			(at -2.050034 -49.725072 270)
			(size 0.519938 1.4986)
			(layers "F.Cu" "F.Mask" "F.Paste")
			(net "GND")
		)
		(pad "18" smd rect
			(at -2.050034 -48.874934 270)
			(size 0.519938 1.4986)
			(layers "F.Cu" "F.Mask" "F.Paste")
			(net "M_F_CPU0_SA_DQ<8>")
		)
		(pad "19" smd rect
			(at -2.050034 -48.02505 270)
			(size 0.519938 1.4986)
			(layers "F.Cu" "F.Mask" "F.Paste")
			(net "GND")
		)
		(pad "20" smd rect
			(at -2.050034 -47.174912 270)
			(size 0.519938 1.4986)
			(layers "F.Cu" "F.Mask" "F.Paste")
			(net "M_F_CPU0_SA_DQ<9>")
		)
		(pad "21" smd rect
			(at -2.050034 -46.325028 270)
			(size 0.519938 1.4986)
			(layers "F.Cu" "F.Mask" "F.Paste")
			(net "GND")
		)
		(pad "22" smd rect
			(at -2.050034 -45.47489 270)
			(size 0.519938 1.4986)
			(layers "F.Cu" "F.Mask" "F.Paste")
			(net "M_F_CPU0_SA_DQS_DP<1>")
		)
		(pad "23" smd rect
			(at -2.050034 -44.625006 270)
			(size 0.519938 1.4986)
			(layers "F.Cu" "F.Mask" "F.Paste")
			(net "M_F_CPU0_SA_DQS_DN<1>")
		)
		(pad "24" smd rect
			(at -2.050034 -43.775122 270)
			(size 0.519938 1.4986)
			(layers "F.Cu" "F.Mask" "F.Paste")
			(net "GND")
		)
		(pad "25" smd rect
			(at -2.050034 -42.924984 270)
			(size 0.519938 1.4986)
			(layers "F.Cu" "F.Mask" "F.Paste")
			(net "M_F_CPU0_SA_DQ<12>")
		)
		(pad "26" smd rect
			(at -2.050034 -42.0751 270)
			(size 0.519938 1.4986)
			(layers "F.Cu" "F.Mask" "F.Paste")
			(net "GND")
		)
		(pad "27" smd rect
			(at -2.050034 -41.224962 270)
			(size 0.519938 1.4986)
			(layers "F.Cu" "F.Mask" "F.Paste")
			(net "M_F_CPU0_SA_DQ<13>")
		)
		(pad "28" smd rect
			(at -2.050034 -40.375078 270)
			(size 0.519938 1.4986)
			(layers "F.Cu" "F.Mask" "F.Paste")
			(net "GND")
		)
		(pad "29" smd rect
			(at -2.050034 -39.52494 270)
			(size 0.519938 1.4986)
			(layers "F.Cu" "F.Mask" "F.Paste")
			(net "M_F_CPU0_SA_DQ<16>")
		)
		(pad "30" smd rect
			(at -2.050034 -38.675056 270)
			(size 0.519938 1.4986)
			(layers "F.Cu" "F.Mask" "F.Paste")
			(net "GND")
		)
		(pad "31" smd rect
			(at -2.050034 -37.824918 270)
			(size 0.519938 1.4986)
			(layers "F.Cu" "F.Mask" "F.Paste")
			(net "M_F_CPU0_SA_DQ<17>")
		)
		(pad "32" smd rect
			(at -2.050034 -36.975034 270)
			(size 0.519938 1.4986)
			(layers "F.Cu" "F.Mask" "F.Paste")
			(net "GND")
		)
		(pad "33" smd rect
			(at -2.050034 -36.124896 270)
			(size 0.519938 1.4986)
			(layers "F.Cu" "F.Mask" "F.Paste")
			(net "M_F_CPU0_SA_DQS_DP<2>")
		)
		(pad "34" smd rect
			(at -2.050034 -35.275012 270)
			(size 0.519938 1.4986)
			(layers "F.Cu" "F.Mask" "F.Paste")
			(net "M_F_CPU0_SA_DQS_DN<2>")
		)
		(pad "35" smd rect
			(at -2.050034 -34.425128 270)
			(size 0.519938 1.4986)
			(layers "F.Cu" "F.Mask" "F.Paste")
			(net "GND")
		)
		(pad "36" smd rect
			(at -2.050034 -33.57499 270)
			(size 0.519938 1.4986)
			(layers "F.Cu" "F.Mask" "F.Paste")
			(net "M_F_CPU0_SA_DQ<20>")
		)
		(pad "37" smd rect
			(at -2.050034 -32.725106 270)
			(size 0.519938 1.4986)
			(layers "F.Cu" "F.Mask" "F.Paste")
			(net "GND")
		)
		(pad "38" smd rect
			(at -2.050034 -31.874968 270)
			(size 0.519938 1.4986)
			(layers "F.Cu" "F.Mask" "F.Paste")
			(net "M_F_CPU0_SA_DQ<21>")
		)
		(pad "39" smd rect
			(at -2.050034 -31.025084 270)
			(size 0.519938 1.4986)
			(layers "F.Cu" "F.Mask" "F.Paste")
			(net "GND")
		)
		(pad "40" smd rect
			(at -2.050034 -30.174946 270)
			(size 0.519938 1.4986)
			(layers "F.Cu" "F.Mask" "F.Paste")
			(net "M_F_CPU0_SA_DQ<24>")
		)
		(pad "41" smd rect
			(at -2.050034 -29.325062 270)
			(size 0.519938 1.4986)
			(layers "F.Cu" "F.Mask" "F.Paste")
			(net "GND")
		)
		(pad "42" smd rect
			(at -2.050034 -28.474924 270)
			(size 0.519938 1.4986)
			(layers "F.Cu" "F.Mask" "F.Paste")
			(net "M_F_CPU0_SA_DQ<25>")
		)
		(pad "43" smd rect
			(at -2.050034 -27.62504 270)
			(size 0.519938 1.4986)
			(layers "F.Cu" "F.Mask" "F.Paste")
			(net "GND")
		)
		(pad "44" smd rect
			(at -2.050034 -26.774902 270)
			(size 0.519938 1.4986)
			(layers "F.Cu" "F.Mask" "F.Paste")
			(net "M_F_CPU0_SA_DQS_DP<3>")
		)
		(pad "45" smd rect
			(at -2.050034 -25.925018 270)
			(size 0.519938 1.4986)
			(layers "F.Cu" "F.Mask" "F.Paste")
			(net "M_F_CPU0_SA_DQS_DN<3>")
		)
		(pad "46" smd rect
			(at -2.050034 -25.07488 270)
			(size 0.519938 1.4986)
			(layers "F.Cu" "F.Mask" "F.Paste")
			(net "GND")
		)
		(pad "47" smd rect
			(at -2.050034 -24.224996 270)
			(size 0.519938 1.4986)
			(layers "F.Cu" "F.Mask" "F.Paste")
			(net "M_F_CPU0_SA_DQ<28>")
		)
		(pad "48" smd rect
			(at -2.050034 -23.375112 270)
			(size 0.519938 1.4986)
			(layers "F.Cu" "F.Mask" "F.Paste")
			(net "GND")
		)
		(pad "49" smd rect
			(at -2.050034 -22.524974 270)
			(size 0.519938 1.4986)
			(layers "F.Cu" "F.Mask" "F.Paste")
			(net "M_F_CPU0_SA_DQ<29>")
		)
		(pad "50" smd rect
			(at -2.050034 -21.67509 270)
			(size 0.519938 1.4986)
			(layers "F.Cu" "F.Mask" "F.Paste")
			(net "GND")
		)
		(pad "51" smd rect
			(at -2.050034 -20.824952 270)
			(size 0.519938 1.4986)
			(layers "F.Cu" "F.Mask" "F.Paste")
			(net "M_F_CPU0_SA_CB<0>")
		)
		(pad "52" smd rect
			(at -2.050034 -19.975068 270)
			(size 0.519938 1.4986)
			(layers "F.Cu" "F.Mask" "F.Paste")
			(net "GND")
		)
		(pad "53" smd rect
			(at -2.050034 -19.12493 270)
			(size 0.519938 1.4986)
			(layers "F.Cu" "F.Mask" "F.Paste")
			(net "M_F_CPU0_SA_CB<1>")
		)
		(pad "54" smd rect
			(at -2.050034 -18.275046 270)
			(size 0.519938 1.4986)
			(layers "F.Cu" "F.Mask" "F.Paste")
			(net "GND")
		)
		(pad "55" smd rect
			(at -2.050034 -17.424908 270)
			(size 0.519938 1.4986)
			(layers "F.Cu" "F.Mask" "F.Paste")
			(net "M_F_CPU0_SA_DQS_DP<4>")
		)
		(pad "56" smd rect
			(at -2.050034 -16.575024 270)
			(size 0.519938 1.4986)
			(layers "F.Cu" "F.Mask" "F.Paste")
			(net "M_F_CPU0_SA_DQS_DN<4>")
		)
		(pad "57" smd rect
			(at -2.050034 -15.724886 270)
			(size 0.519938 1.4986)
			(layers "F.Cu" "F.Mask" "F.Paste")
			(net "GND")
		)
		(pad "58" smd rect
			(at -2.050034 -14.875002 270)
			(size 0.519938 1.4986)
			(layers "F.Cu" "F.Mask" "F.Paste")
			(net "M_F_CPU0_SA_CB<4>")
		)
		(pad "59" smd rect
			(at -2.050034 -14.025118 270)
			(size 0.519938 1.4986)
			(layers "F.Cu" "F.Mask" "F.Paste")
			(net "GND")
		)
		(pad "60" smd rect
			(at -2.050034 -13.17498 270)
			(size 0.519938 1.4986)
			(layers "F.Cu" "F.Mask" "F.Paste")
			(net "M_F_CPU0_SA_CB<5>")
		)
		(pad "61" smd rect
			(at -2.050034 -12.325096 270)
			(size 0.519938 1.4986)
			(layers "F.Cu" "F.Mask" "F.Paste")
			(net "GND")
		)
		(pad "62" smd rect
			(at -2.050034 -11.474958 270)
			(size 0.519938 1.4986)
			(layers "F.Cu" "F.Mask" "F.Paste")
			(net "M_F_CPU0_ALERT_N")
		)
		(pad "63" smd rect
			(at -2.050034 -10.625074 270)
			(size 0.519938 1.4986)
			(layers "F.Cu" "F.Mask" "F.Paste")
			(net "GND")
		)
		(pad "64" smd rect
			(at -2.050034 -9.774936 270)
			(size 0.519938 1.4986)
			(layers "F.Cu" "F.Mask" "F.Paste")
			(net "M_F_CPU0_SA_CS_N<0>")
		)
		(pad "65" smd rect
			(at -2.050034 -8.925052 270)
			(size 0.519938 1.4986)
			(layers "F.Cu" "F.Mask" "F.Paste")
			(net "GND")
		)
		(pad "66" smd rect
			(at -2.050034 -8.074914 270)
			(size 0.519938 1.4986)
			(layers "F.Cu" "F.Mask" "F.Paste")
			(net "M_F_CPU0_SA_CA<0>")
		)
		(pad "67" smd rect
			(at -2.050034 -7.22503 270)
			(size 0.519938 1.4986)
			(layers "F.Cu" "F.Mask" "F.Paste")
			(net "GND")
		)
		(pad "68" smd rect
			(at -2.050034 -6.374892 270)
			(size 0.519938 1.4986)
			(layers "F.Cu" "F.Mask" "F.Paste")
			(net "M_F_CPU0_SA_CA<2>")
		)
		(pad "69" smd rect
			(at -2.050034 -5.525008 270)
			(size 0.519938 1.4986)
			(layers "F.Cu" "F.Mask" "F.Paste")
			(net "GND")
		)
		(pad "70" smd rect
			(at -2.050034 -4.675124 270)
			(size 0.519938 1.4986)
			(layers "F.Cu" "F.Mask" "F.Paste")
			(net "M_F_CPU0_SA_CA<4>")
		)
		(pad "71" smd rect
			(at -2.050034 -3.824986 270)
			(size 0.519938 1.4986)
			(layers "F.Cu" "F.Mask" "F.Paste")
			(net "GND")
		)
		(pad "72" smd rect
			(at -2.050034 -2.975102 270)
			(size 0.519938 1.4986)
			(layers "F.Cu" "F.Mask" "F.Paste")
			(net "M_F_CPU0_SA_CA<6>")
		)
		(pad "73" smd rect
			(at -2.050034 -2.124964 270)
			(size 0.519938 1.4986)
			(layers "F.Cu" "F.Mask" "F.Paste")
			(net "GND")
		)
		(pad "74" smd rect
			(at -2.050034 -1.27508 270)
			(size 0.519938 1.4986)
			(layers "F.Cu" "F.Mask" "F.Paste")
			(net "M_F_CPU0_SA_PAR")
		)
		(pad "75" smd rect
			(at -2.050034 -0.424942 270)
			(size 0.519938 1.4986)
			(layers "F.Cu" "F.Mask" "F.Paste")
			(net "GND")
		)
		(pad "76" smd rect
			(at -2.050034 5.525008 270)
			(size 0.519938 1.4986)
			(layers "F.Cu" "F.Mask" "F.Paste")
			(net "M_F_CPU0_SB_CA<0>")
		)
		(pad "77" smd rect
			(at -2.050034 6.374892 270)
			(size 0.519938 1.4986)
			(layers "F.Cu" "F.Mask" "F.Paste")
			(net "GND")
		)
		(pad "78" smd rect
			(at -2.050034 7.22503 270)
			(size 0.519938 1.4986)
			(layers "F.Cu" "F.Mask" "F.Paste")
			(net "M_F_CPU0_SB_CA<2>")
		)
		(pad "79" smd rect
			(at -2.050034 8.074914 270)
			(size 0.519938 1.4986)
			(layers "F.Cu" "F.Mask" "F.Paste")
			(net "GND")
		)
		(pad "80" smd rect
			(at -2.050034 8.925052 270)
			(size 0.519938 1.4986)
			(layers "F.Cu" "F.Mask" "F.Paste")
			(net "M_F_CPU0_SB_CA<4>")
		)
		(pad "81" smd rect
			(at -2.050034 9.774936 270)
			(size 0.519938 1.4986)
			(layers "F.Cu" "F.Mask" "F.Paste")
			(net "GND")
		)
		(pad "82" smd rect
			(at -2.050034 10.625074 270)
			(size 0.519938 1.4986)
			(layers "F.Cu" "F.Mask" "F.Paste")
			(net "M_F_CPU0_SB_CA<6>")
		)
		(pad "83" smd rect
			(at -2.050034 11.474958 270)
			(size 0.519938 1.4986)
			(layers "F.Cu" "F.Mask" "F.Paste")
			(net "GND")
		)
		(pad "84" smd rect
			(at -2.050034 12.325096 270)
			(size 0.519938 1.4986)
			(layers "F.Cu" "F.Mask" "F.Paste")
			(net "M_F_CPU0_SB_CS_N<0>")
		)
		(pad "85" smd rect
			(at -2.050034 13.17498 270)
			(size 0.519938 1.4986)
			(layers "F.Cu" "F.Mask" "F.Paste")
			(net "GND")
		)
		(pad "86" smd rect
			(at -2.050034 14.025118 270)
			(size 0.519938 1.4986)
			(layers "F.Cu" "F.Mask" "F.Paste")
			(net "M_F_CPU0_SA_RSP<0>")
		)
		(pad "87" smd rect
			(at -2.050034 14.875002 270)
			(size 0.519938 1.4986)
			(layers "F.Cu" "F.Mask" "F.Paste")
			(net "M_F_CPU0_SB_RSP<0>")
		)
		(pad "88" smd rect
			(at -2.050034 15.724886 270)
			(size 0.519938 1.4986)
			(layers "F.Cu" "F.Mask" "F.Paste")
			(net "GND")
		)
		(pad "89" smd rect
			(at -2.050034 16.575024 270)
			(size 0.519938 1.4986)
			(layers "F.Cu" "F.Mask" "F.Paste")
			(net "M_F_CPU0_SB_CB<4>")
		)
		(pad "90" smd rect
			(at -2.050034 17.424908 270)
			(size 0.519938 1.4986)
			(layers "F.Cu" "F.Mask" "F.Paste")
			(net "GND")
		)
		(pad "91" smd rect
			(at -2.050034 18.275046 270)
			(size 0.519938 1.4986)
			(layers "F.Cu" "F.Mask" "F.Paste")
			(net "M_F_CPU0_SB_CB<5>")
		)
		(pad "92" smd rect
			(at -2.050034 19.12493 270)
			(size 0.519938 1.4986)
			(layers "F.Cu" "F.Mask" "F.Paste")
			(net "GND")
		)
		(pad "93" smd rect
			(at -2.050034 19.975068 270)
			(size 0.519938 1.4986)
			(layers "F.Cu" "F.Mask" "F.Paste")
			(net "M_F_CPU0_SB_DQS_DP<9>")
		)
		(pad "94" smd rect
			(at -2.050034 20.824952 270)
			(size 0.519938 1.4986)
			(layers "F.Cu" "F.Mask" "F.Paste")
			(net "M_F_CPU0_SB_DQS_DN<9>")
		)
		(pad "95" smd rect
			(at -2.050034 21.67509 270)
			(size 0.519938 1.4986)
			(layers "F.Cu" "F.Mask" "F.Paste")
			(net "GND")
		)
		(pad "96" smd rect
			(at -2.050034 22.524974 270)
			(size 0.519938 1.4986)
			(layers "F.Cu" "F.Mask" "F.Paste")
			(net "M_F_CPU0_SB_CB<0>")
		)
		(pad "97" smd rect
			(at -2.050034 23.375112 270)
			(size 0.519938 1.4986)
			(layers "F.Cu" "F.Mask" "F.Paste")
			(net "GND")
		)
		(pad "98" smd rect
			(at -2.050034 24.224996 270)
			(size 0.519938 1.4986)
			(layers "F.Cu" "F.Mask" "F.Paste")
			(net "M_F_CPU0_SB_CB<1>")
		)
		(pad "99" smd rect
			(at -2.050034 25.07488 270)
			(size 0.519938 1.4986)
			(layers "F.Cu" "F.Mask" "F.Paste")
			(net "GND")
		)
		(pad "100" smd rect
			(at -2.050034 25.925018 270)
			(size 0.519938 1.4986)
			(layers "F.Cu" "F.Mask" "F.Paste")
			(net "M_F_CPU0_SB_DQ<0>")
		)
		(pad "101" smd rect
			(at -2.050034 26.774902 270)
			(size 0.519938 1.4986)
			(layers "F.Cu" "F.Mask" "F.Paste")
			(net "GND")
		)
		(pad "102" smd rect
			(at -2.050034 27.62504 270)
			(size 0.519938 1.4986)
			(layers "F.Cu" "F.Mask" "F.Paste")
			(net "M_F_CPU0_SB_DQ<1>")
		)
		(pad "103" smd rect
			(at -2.050034 28.474924 270)
			(size 0.519938 1.4986)
			(layers "F.Cu" "F.Mask" "F.Paste")
			(net "GND")
		)
		(pad "104" smd rect
			(at -2.050034 29.325062 270)
			(size 0.519938 1.4986)
			(layers "F.Cu" "F.Mask" "F.Paste")
			(net "M_F_CPU0_SB_DQS_DP<0>")
		)
		(pad "105" smd rect
			(at -2.050034 30.174946 270)
			(size 0.519938 1.4986)
			(layers "F.Cu" "F.Mask" "F.Paste")
			(net "M_F_CPU0_SB_DQS_DN<0>")
		)
		(pad "106" smd rect
			(at -2.050034 31.025084 270)
			(size 0.519938 1.4986)
			(layers "F.Cu" "F.Mask" "F.Paste")
			(net "GND")
		)
		(pad "107" smd rect
			(at -2.050034 31.874968 270)
			(size 0.519938 1.4986)
			(layers "F.Cu" "F.Mask" "F.Paste")
			(net "M_F_CPU0_SB_DQ<4>")
		)
		(pad "108" smd rect
			(at -2.050034 32.725106 270)
			(size 0.519938 1.4986)
			(layers "F.Cu" "F.Mask" "F.Paste")
			(net "GND")
		)
		(pad "109" smd rect
			(at -2.050034 33.57499 270)
			(size 0.519938 1.4986)
			(layers "F.Cu" "F.Mask" "F.Paste")
			(net "M_F_CPU0_SB_DQ<5>")
		)
		(pad "110" smd rect
			(at -2.050034 34.425128 270)
			(size 0.519938 1.4986)
			(layers "F.Cu" "F.Mask" "F.Paste")
			(net "GND")
		)
		(pad "111" smd rect
			(at -2.050034 35.275012 270)
			(size 0.519938 1.4986)
			(layers "F.Cu" "F.Mask" "F.Paste")
			(net "M_F_CPU0_SB_DQ<8>")
		)
		(pad "112" smd rect
			(at -2.050034 36.124896 270)
			(size 0.519938 1.4986)
			(layers "F.Cu" "F.Mask" "F.Paste")
			(net "GND")
		)
	)
)
